(kicad_pcb
	(version 20260206)
	(generator "pcbnew")
	(generator_version "10.0")
	(general
		(thickness 1.6)
		(legacy_teardrops no)
	)
	(paper "A4")
	(title_block
		(title "Bryce Canyon_F.DPB_16315-1-OCP.brd")
		(comment 1 "Bryce Canyon / footprint 2079 of 2223 (IO1), pads 167-196 of 202")
	)
	(layers
		(0 "F.Cu" signal "TOP")
		(4 "In1.Cu" signal "L2GND")
		(6 "In2.Cu" signal "L3")
		(8 "In3.Cu" signal "L4GND")
		(10 "In4.Cu" signal "L5")
		(12 "In5.Cu" signal "L6VCC")
		(14 "In6.Cu" signal "L7VCC")
		(16 "In7.Cu" signal "L8")
		(18 "In8.Cu" signal "L9GND")
		(20 "In9.Cu" signal "L10")
		(22 "In10.Cu" signal "L11GND")
		(2 "B.Cu" signal "BOTTOM")
		(9 "F.Adhes" user "F.Adhesive")
		(11 "B.Adhes" user "B.Adhesive")
		(13 "F.Paste" user "Package Geometry/Pastemask Top")
		(15 "B.Paste" user "Package Geometry/Pastemask Bottom")
		(5 "F.SilkS" user "Ref Des/Silkscreen Top")
		(7 "B.SilkS" user "Ref Des/Silkscreen Bottom")
		(1 "F.Mask" user "Board Geometry/Soldermask Top")
		(3 "B.Mask" user "Board Geometry/Soldermask Bottom")
		(17 "Dwgs.User" user "User.Drawings")
		(19 "Cmts.User" user "User.Comments")
		(21 "Eco1.User" user "User.Eco1")
		(23 "Eco2.User" user "User.Eco2")
		(25 "Edge.Cuts" user "Board Geometry/Outline")
		(27 "Margin" user)
		(31 "F.CrtYd" user "Package Geometry/Place Bound Top")
		(29 "B.CrtYd" user "Package Geometry/Place Bound Bottom")
		(35 "F.Fab" user "Ref Des/Assembly Top")
		(33 "B.Fab" user "Ref Des/Assembly Bottom")
	)
	(footprint ""
		(layer "B.Cu")
		(at 143.34998 -30.550104 180)
		(property "Reference" "IO1"
			(at 0 0 0)
			(layer "B.SilkS")
			(hide yes)
			(effects
				(font
					(size 1.27 1.27)
				)
				(justify mirror)
			)
		)
		(property "Value" "DM-AMP-CONN200-13R-6-GP-01"
			(at 47.5488 -16.5862 180)
			(unlocked yes)
			(layer "B.Fab")
			(hide yes)
			(effects
				(font
					(size 1.016 1.016)
					(thickness 0.1524)
				)
				(justify mirror)
			)
		)
		(property "Device Type" "DMFIT-200P-384346H577-01"
			(at 47.5488 -18.1102 180)
			(unlocked yes)
			(layer "B.Fab")
			(hide yes)
			(effects
				(font
					(size 1.016 1.016)
					(thickness 0.1524)
				)
				(justify mirror)
			)
		)
		(duplicate_pad_numbers_are_jumpers no)
		(pad "GND53" thru_hole circle
			(at 26.999946 -10.700004)
			(size 0.762 0.762)
			(drill 0.359918)
			(layers "*.Cu" "*.Mask")
			(remove_unused_layers no)
			(net "GND")
			(clearance 0.1651)
			(thermal_gap 0.1651)
		)
		(pad "GND54" thru_hole circle
			(at 26.999946 -14.299946)
			(size 0.762 0.762)
			(drill 0.359918)
			(layers "*.Cu" "*.Mask")
			(remove_unused_layers no)
			(net "GND")
			(clearance 0.1651)
			(thermal_gap 0.1651)
		)
		(pad "GND55" thru_hole circle
			(at 28.800044 -2.500122)
			(size 0.762 0.762)
			(drill 0.359918)
			(layers "*.Cu" "*.Mask")
			(remove_unused_layers no)
			(net "GND")
			(clearance 0.1651)
			(thermal_gap 0.1651)
		)
		(pad "GND56" thru_hole circle
			(at 28.800044 -6.100064)
			(size 0.762 0.762)
			(drill 0.359918)
			(layers "*.Cu" "*.Mask")
			(remove_unused_layers no)
			(net "GND")
			(clearance 0.1651)
			(thermal_gap 0.1651)
		)
		(pad "GND57" thru_hole circle
			(at 28.800044 -9.700006)
			(size 0.762 0.762)
			(drill 0.359918)
			(layers "*.Cu" "*.Mask")
			(remove_unused_layers no)
			(net "GND")
			(clearance 0.1651)
			(thermal_gap 0.1651)
		)
		(pad "GND58" thru_hole circle
			(at 28.800044 -13.299948)
			(size 0.762 0.762)
			(drill 0.359918)
			(layers "*.Cu" "*.Mask")
			(remove_unused_layers no)
			(net "GND")
			(clearance 0.1651)
			(thermal_gap 0.1651)
		)
		(pad "GND59" thru_hole circle
			(at 30.599888 0.100076)
			(size 0.762 0.762)
			(drill 0.359918)
			(layers "*.Cu" "*.Mask")
			(remove_unused_layers no)
			(net "GND")
			(clearance 0.1651)
			(thermal_gap 0.1651)
		)
		(pad "GND60" thru_hole circle
			(at 30.599888 -3.50012)
			(size 0.762 0.762)
			(drill 0.359918)
			(layers "*.Cu" "*.Mask")
			(remove_unused_layers no)
			(net "GND")
			(clearance 0.1651)
			(thermal_gap 0.1651)
		)
		(pad "GND61" thru_hole circle
			(at 30.599888 -7.100062)
			(size 0.762 0.762)
			(drill 0.359918)
			(layers "*.Cu" "*.Mask")
			(remove_unused_layers no)
			(net "GND")
			(clearance 0.1651)
			(thermal_gap 0.1651)
		)
		(pad "GND62" thru_hole circle
			(at 30.599888 -10.700004)
			(size 0.762 0.762)
			(drill 0.359918)
			(layers "*.Cu" "*.Mask")
			(remove_unused_layers no)
			(net "GND")
			(clearance 0.1651)
			(thermal_gap 0.1651)
		)
		(pad "GND63" thru_hole circle
			(at 30.599888 -14.299946)
			(size 0.762 0.762)
			(drill 0.359918)
			(layers "*.Cu" "*.Mask")
			(remove_unused_layers no)
			(net "GND")
			(clearance 0.1651)
			(thermal_gap 0.1651)
		)
		(pad "GND64" thru_hole circle
			(at 32.399986 -2.500122)
			(size 0.762 0.762)
			(drill 0.359918)
			(layers "*.Cu" "*.Mask")
			(remove_unused_layers no)
			(net "GND")
			(clearance 0.1651)
			(thermal_gap 0.1651)
		)
		(pad "GND65" thru_hole circle
			(at 32.399986 -6.100064)
			(size 0.762 0.762)
			(drill 0.359918)
			(layers "*.Cu" "*.Mask")
			(remove_unused_layers no)
			(net "GND")
			(clearance 0.1651)
			(thermal_gap 0.1651)
		)
		(pad "GND66" thru_hole circle
			(at 32.399986 -9.700006)
			(size 0.762 0.762)
			(drill 0.359918)
			(layers "*.Cu" "*.Mask")
			(remove_unused_layers no)
			(net "GND")
			(clearance 0.1651)
			(thermal_gap 0.1651)
		)
		(pad "GND67" thru_hole circle
			(at 32.399986 -13.299948)
			(size 0.762 0.762)
			(drill 0.359918)
			(layers "*.Cu" "*.Mask")
			(remove_unused_layers no)
			(net "GND")
			(clearance 0.1651)
			(thermal_gap 0.1651)
		)
		(pad "GND68" thru_hole circle
			(at 34.200084 0.100076)
			(size 0.762 0.762)
			(drill 0.359918)
			(layers "*.Cu" "*.Mask")
			(remove_unused_layers no)
			(net "GND")
			(clearance 0.1651)
			(thermal_gap 0.1651)
		)
		(pad "GND69" thru_hole circle
			(at 34.200084 -3.50012)
			(size 0.762 0.762)
			(drill 0.359918)
			(layers "*.Cu" "*.Mask")
			(remove_unused_layers no)
			(net "GND")
			(clearance 0.1651)
			(thermal_gap 0.1651)
		)
		(pad "GND70" thru_hole circle
			(at 34.200084 -7.100062)
			(size 0.762 0.762)
			(drill 0.359918)
			(layers "*.Cu" "*.Mask")
			(remove_unused_layers no)
			(net "GND")
			(clearance 0.1651)
			(thermal_gap 0.1651)
		)
		(pad "GND71" thru_hole circle
			(at 34.200084 -10.700004)
			(size 0.762 0.762)
			(drill 0.359918)
			(layers "*.Cu" "*.Mask")
			(remove_unused_layers no)
			(net "GND")
			(clearance 0.1651)
			(thermal_gap 0.1651)
		)
		(pad "GND72" thru_hole circle
			(at 34.200084 -14.299946)
			(size 0.762 0.762)
			(drill 0.359918)
			(layers "*.Cu" "*.Mask")
			(remove_unused_layers no)
			(net "GND")
			(clearance 0.1651)
			(thermal_gap 0.1651)
		)
		(pad "H1" thru_hole circle
			(at 0 -12.199874)
			(size 0.664718 0.664718)
			(drill 0.359918)
			(layers "*.Cu" "*.Mask")
			(remove_unused_layers no)
			(net "PCIE_COMP_A_TO_IOM_A_8_DP")
			(clearance 0.264414)
			(padstack
				(mode custom)
				(layer "In1.Cu"
					(shape circle)
					(size 0.664718 0.664718)
					(clearance 0.264414)
				)
				(layer "In2.Cu"
					(shape circle)
					(size 0.664718 0.664718)
					(clearance 0.264414)
				)
				(layer "In3.Cu"
					(shape circle)
					(size 0.664718 0.664718)
					(clearance 0.264414)
				)
				(layer "In4.Cu"
					(shape circle)
					(size 0.664718 0.664718)
					(clearance 0.264414)
				)
				(layer "In5.Cu"
					(shape circle)
					(size 0.664718 0.664718)
					(clearance 0.264414)
				)
				(layer "In6.Cu"
					(shape circle)
					(size 0.762 0.762)
					(clearance 0.1651)
				)
				(layer "In7.Cu"
					(shape circle)
					(size 0.762 0.762)
					(clearance 0.1651)
				)
				(layer "In8.Cu"
					(shape circle)
					(size 0.762 0.762)
					(clearance 0.1651)
				)
				(layer "In9.Cu"
					(shape circle)
					(size 0.762 0.762)
					(clearance 0.1651)
				)
				(layer "In10.Cu"
					(shape circle)
					(size 0.762 0.762)
					(clearance 0.1651)
				)
				(layer "B.Cu"
					(shape circle)
					(size 0.762 0.762)
					(thermal_gap 0.1651)
					(clearance 0.1651)
				)
			)
		)
		(pad "H2" thru_hole circle
			(at 1.800098 -13.200126)
			(size 0.664718 0.664718)
			(drill 0.359918)
			(layers "*.Cu" "*.Mask")
			(remove_unused_layers no)
			(net "PCIE_COMP_A_TO_IOM_A_9_DP")
			(clearance 0.264414)
			(padstack
				(mode custom)
				(layer "In1.Cu"
					(shape circle)
					(size 0.664718 0.664718)
					(clearance 0.264414)
				)
				(layer "In2.Cu"
					(shape circle)
					(size 0.664718 0.664718)
					(clearance 0.264414)
				)
				(layer "In3.Cu"
					(shape circle)
					(size 0.664718 0.664718)
					(clearance 0.264414)
				)
				(layer "In4.Cu"
					(shape circle)
					(size 0.664718 0.664718)
					(clearance 0.264414)
				)
				(layer "In5.Cu"
					(shape circle)
					(size 0.664718 0.664718)
					(clearance 0.264414)
				)
				(layer "In6.Cu"
					(shape circle)
					(size 0.762 0.762)
					(clearance 0.1651)
				)
				(layer "In7.Cu"
					(shape circle)
					(size 0.762 0.762)
					(clearance 0.1651)
				)
				(layer "In8.Cu"
					(shape circle)
					(size 0.762 0.762)
					(clearance 0.1651)
				)
				(layer "In9.Cu"
					(shape circle)
					(size 0.762 0.762)
					(clearance 0.1651)
				)
				(layer "In10.Cu"
					(shape circle)
					(size 0.762 0.762)
					(clearance 0.1651)
				)
				(layer "B.Cu"
					(shape circle)
					(size 0.762 0.762)
					(thermal_gap 0.1651)
					(clearance 0.1651)
				)
			)
		)
		(pad "H3" thru_hole circle
			(at 3.599942 -12.199874)
			(size 0.664718 0.664718)
			(drill 0.359918)
			(layers "*.Cu" "*.Mask")
			(remove_unused_layers no)
			(net "PCIE_COMP_A_TO_IOM_A_10_DP")
			(clearance 0.264414)
			(padstack
				(mode custom)
				(layer "In1.Cu"
					(shape circle)
					(size 0.664718 0.664718)
					(clearance 0.264414)
				)
				(layer "In2.Cu"
					(shape circle)
					(size 0.664718 0.664718)
					(clearance 0.264414)
				)
				(layer "In3.Cu"
					(shape circle)
					(size 0.664718 0.664718)
					(clearance 0.264414)
				)
				(layer "In4.Cu"
					(shape circle)
					(size 0.664718 0.664718)
					(clearance 0.264414)
				)
				(layer "In5.Cu"
					(shape circle)
					(size 0.664718 0.664718)
					(clearance 0.264414)
				)
				(layer "In6.Cu"
					(shape circle)
					(size 0.762 0.762)
					(clearance 0.1651)
				)
				(layer "In7.Cu"
					(shape circle)
					(size 0.762 0.762)
					(clearance 0.1651)
				)
				(layer "In8.Cu"
					(shape circle)
					(size 0.762 0.762)
					(clearance 0.1651)
				)
				(layer "In9.Cu"
					(shape circle)
					(size 0.762 0.762)
					(clearance 0.1651)
				)
				(layer "In10.Cu"
					(shape circle)
					(size 0.762 0.762)
					(clearance 0.1651)
				)
				(layer "B.Cu"
					(shape circle)
					(size 0.762 0.762)
					(thermal_gap 0.1651)
					(clearance 0.1651)
				)
			)
		)
		(pad "H4" thru_hole circle
			(at 5.40004 -13.200126)
			(size 0.664718 0.664718)
			(drill 0.359918)
			(layers "*.Cu" "*.Mask")
			(remove_unused_layers no)
			(net "PCIE_COMP_A_TO_IOM_A_11_DP")
			(clearance 0.264414)
			(padstack
				(mode custom)
				(layer "In1.Cu"
					(shape circle)
					(size 0.664718 0.664718)
					(clearance 0.264414)
				)
				(layer "In2.Cu"
					(shape circle)
					(size 0.664718 0.664718)
					(clearance 0.264414)
				)
				(layer "In3.Cu"
					(shape circle)
					(size 0.664718 0.664718)
					(clearance 0.264414)
				)
				(layer "In4.Cu"
					(shape circle)
					(size 0.664718 0.664718)
					(clearance 0.264414)
				)
				(layer "In5.Cu"
					(shape circle)
					(size 0.664718 0.664718)
					(clearance 0.264414)
				)
				(layer "In6.Cu"
					(shape circle)
					(size 0.762 0.762)
					(clearance 0.1651)
				)
				(layer "In7.Cu"
					(shape circle)
					(size 0.762 0.762)
					(clearance 0.1651)
				)
				(layer "In8.Cu"
					(shape circle)
					(size 0.762 0.762)
					(clearance 0.1651)
				)
				(layer "In9.Cu"
					(shape circle)
					(size 0.762 0.762)
					(clearance 0.1651)
				)
				(layer "In10.Cu"
					(shape circle)
					(size 0.762 0.762)
					(clearance 0.1651)
				)
				(layer "B.Cu"
					(shape circle)
					(size 0.762 0.762)
					(thermal_gap 0.1651)
					(clearance 0.1651)
				)
			)
		)
		(pad "H5" thru_hole circle
			(at 7.199884 -12.199874)
			(size 0.664718 0.664718)
			(drill 0.359918)
			(layers "*.Cu" "*.Mask")
			(remove_unused_layers no)
			(net "PCIE_COMP_A_TO_IOM_A_12_DP")
			(clearance 0.264414)
			(padstack
				(mode custom)
				(layer "In1.Cu"
					(shape circle)
					(size 0.664718 0.664718)
					(clearance 0.264414)
				)
				(layer "In2.Cu"
					(shape circle)
					(size 0.664718 0.664718)
					(clearance 0.264414)
				)
				(layer "In3.Cu"
					(shape circle)
					(size 0.664718 0.664718)
					(clearance 0.264414)
				)
				(layer "In4.Cu"
					(shape circle)
					(size 0.664718 0.664718)
					(clearance 0.264414)
				)
				(layer "In5.Cu"
					(shape circle)
					(size 0.664718 0.664718)
					(clearance 0.264414)
				)
				(layer "In6.Cu"
					(shape circle)
					(size 0.762 0.762)
					(clearance 0.1651)
				)
				(layer "In7.Cu"
					(shape circle)
					(size 0.762 0.762)
					(clearance 0.1651)
				)
				(layer "In8.Cu"
					(shape circle)
					(size 0.762 0.762)
					(clearance 0.1651)
				)
				(layer "In9.Cu"
					(shape circle)
					(size 0.762 0.762)
					(clearance 0.1651)
				)
				(layer "In10.Cu"
					(shape circle)
					(size 0.762 0.762)
					(clearance 0.1651)
				)
				(layer "B.Cu"
					(shape circle)
					(size 0.762 0.762)
					(thermal_gap 0.1651)
					(clearance 0.1651)
				)
			)
		)
		(pad "H6" thru_hole circle
			(at 8.999982 -13.200126)
			(size 0.664718 0.664718)
			(drill 0.359918)
			(layers "*.Cu" "*.Mask")
			(remove_unused_layers no)
			(net "PCIE_COMP_A_TO_IOM_A_13_DP")
			(clearance 0.264414)
			(padstack
				(mode custom)
				(layer "In1.Cu"
					(shape circle)
					(size 0.664718 0.664718)
					(clearance 0.264414)
				)
				(layer "In2.Cu"
					(shape circle)
					(size 0.664718 0.664718)
					(clearance 0.264414)
				)
				(layer "In3.Cu"
					(shape circle)
					(size 0.664718 0.664718)
					(clearance 0.264414)
				)
				(layer "In4.Cu"
					(shape circle)
					(size 0.664718 0.664718)
					(clearance 0.264414)
				)
				(layer "In5.Cu"
					(shape circle)
					(size 0.664718 0.664718)
					(clearance 0.264414)
				)
				(layer "In6.Cu"
					(shape circle)
					(size 0.762 0.762)
					(clearance 0.1651)
				)
				(layer "In7.Cu"
					(shape circle)
					(size 0.762 0.762)
					(clearance 0.1651)
				)
				(layer "In8.Cu"
					(shape circle)
					(size 0.762 0.762)
					(clearance 0.1651)
				)
				(layer "In9.Cu"
					(shape circle)
					(size 0.762 0.762)
					(clearance 0.1651)
				)
				(layer "In10.Cu"
					(shape circle)
					(size 0.762 0.762)
					(clearance 0.1651)
				)
				(layer "B.Cu"
					(shape circle)
					(size 0.762 0.762)
					(thermal_gap 0.1651)
					(clearance 0.1651)
				)
			)
		)
		(pad "H7" thru_hole circle
			(at 10.80008 -12.199874)
			(size 0.664718 0.664718)
			(drill 0.359918)
			(layers "*.Cu" "*.Mask")
			(remove_unused_layers no)
			(net "PCIE_COMP_A_TO_IOM_A_14_DP")
			(clearance 0.264414)
			(padstack
				(mode custom)
				(layer "In1.Cu"
					(shape circle)
					(size 0.664718 0.664718)
					(clearance 0.264414)
				)
				(layer "In2.Cu"
					(shape circle)
					(size 0.664718 0.664718)
					(clearance 0.264414)
				)
				(layer "In3.Cu"
					(shape circle)
					(size 0.664718 0.664718)
					(clearance 0.264414)
				)
				(layer "In4.Cu"
					(shape circle)
					(size 0.664718 0.664718)
					(clearance 0.264414)
				)
				(layer "In5.Cu"
					(shape circle)
					(size 0.664718 0.664718)
					(clearance 0.264414)
				)
				(layer "In6.Cu"
					(shape circle)
					(size 0.762 0.762)
					(clearance 0.1651)
				)
				(layer "In7.Cu"
					(shape circle)
					(size 0.762 0.762)
					(clearance 0.1651)
				)
				(layer "In8.Cu"
					(shape circle)
					(size 0.762 0.762)
					(clearance 0.1651)
				)
				(layer "In9.Cu"
					(shape circle)
					(size 0.762 0.762)
					(clearance 0.1651)
				)
				(layer "In10.Cu"
					(shape circle)
					(size 0.762 0.762)
					(clearance 0.1651)
				)
				(layer "B.Cu"
					(shape circle)
					(size 0.762 0.762)
					(thermal_gap 0.1651)
					(clearance 0.1651)
				)
			)
		)
		(pad "H8" thru_hole circle
			(at 12.599924 -13.200126)
			(size 0.664718 0.664718)
			(drill 0.359918)
			(layers "*.Cu" "*.Mask")
			(remove_unused_layers no)
			(net "PCIE_COMP_A_TO_IOM_A_15_DP")
			(clearance 0.264414)
			(padstack
				(mode custom)
				(layer "In1.Cu"
					(shape circle)
					(size 0.664718 0.664718)
					(clearance 0.264414)
				)
				(layer "In2.Cu"
					(shape circle)
					(size 0.664718 0.664718)
					(clearance 0.264414)
				)
				(layer "In3.Cu"
					(shape circle)
					(size 0.664718 0.664718)
					(clearance 0.264414)
				)
				(layer "In4.Cu"
					(shape circle)
					(size 0.664718 0.664718)
					(clearance 0.264414)
				)
				(layer "In5.Cu"
					(shape circle)
					(size 0.664718 0.664718)
					(clearance 0.264414)
				)
				(layer "In6.Cu"
					(shape circle)
					(size 0.762 0.762)
					(clearance 0.1651)
				)
				(layer "In7.Cu"
					(shape circle)
					(size 0.762 0.762)
					(clearance 0.1651)
				)
				(layer "In8.Cu"
					(shape circle)
					(size 0.762 0.762)
					(clearance 0.1651)
				)
				(layer "In9.Cu"
					(shape circle)
					(size 0.762 0.762)
					(clearance 0.1651)
				)
				(layer "In10.Cu"
					(shape circle)
					(size 0.762 0.762)
					(clearance 0.1651)
				)
				(layer "B.Cu"
					(shape circle)
					(size 0.762 0.762)
					(thermal_gap 0.1651)
					(clearance 0.1651)
				)
			)
		)
		(pad "H9" thru_hole circle
			(at 21.599906 -12.199874)
			(size 0.664718 0.664718)
			(drill 0.359918)
			(layers "*.Cu" "*.Mask")
			(remove_unused_layers no)
			(net "PCIE_COMP_A_TO_IOM_A_16_DP")
			(clearance 0.264414)
			(padstack
				(mode custom)
				(layer "In1.Cu"
					(shape circle)
					(size 0.664718 0.664718)
					(clearance 0.264414)
				)
				(layer "In2.Cu"
					(shape circle)
					(size 0.664718 0.664718)
					(clearance 0.264414)
				)
				(layer "In3.Cu"
					(shape circle)
					(size 0.664718 0.664718)
					(clearance 0.264414)
				)
				(layer "In4.Cu"
					(shape circle)
					(size 0.664718 0.664718)
					(clearance 0.264414)
				)
				(layer "In5.Cu"
					(shape circle)
					(size 0.664718 0.664718)
					(clearance 0.264414)
				)
				(layer "In6.Cu"
					(shape circle)
					(size 0.762 0.762)
					(clearance 0.1651)
				)
				(layer "In7.Cu"
					(shape circle)
					(size 0.762 0.762)
					(clearance 0.1651)
				)
				(layer "In8.Cu"
					(shape circle)
					(size 0.762 0.762)
					(clearance 0.1651)
				)
				(layer "In9.Cu"
					(shape circle)
					(size 0.762 0.762)
					(clearance 0.1651)
				)
				(layer "In10.Cu"
					(shape circle)
					(size 0.762 0.762)
					(clearance 0.1651)
				)
				(layer "B.Cu"
					(shape circle)
					(size 0.762 0.762)
					(thermal_gap 0.1651)
					(clearance 0.1651)
				)
			)
		)
		(pad "H10" thru_hole circle
			(at 23.400004 -13.200126)
			(size 0.664718 0.664718)
			(drill 0.359918)
			(layers "*.Cu" "*.Mask")
			(remove_unused_layers no)
			(net "PCIE_COMP_A_TO_IOM_A_17_DP")
			(clearance 0.264414)
			(padstack
				(mode custom)
				(layer "In1.Cu"
					(shape circle)
					(size 0.664718 0.664718)
					(clearance 0.264414)
				)
				(layer "In2.Cu"
					(shape circle)
					(size 0.664718 0.664718)
					(clearance 0.264414)
				)
				(layer "In3.Cu"
					(shape circle)
					(size 0.664718 0.664718)
					(clearance 0.264414)
				)
				(layer "In4.Cu"
					(shape circle)
					(size 0.664718 0.664718)
					(clearance 0.264414)
				)
				(layer "In5.Cu"
					(shape circle)
					(size 0.664718 0.664718)
					(clearance 0.264414)
				)
				(layer "In6.Cu"
					(shape circle)
					(size 0.762 0.762)
					(clearance 0.1651)
				)
				(layer "In7.Cu"
					(shape circle)
					(size 0.762 0.762)
					(clearance 0.1651)
				)
				(layer "In8.Cu"
					(shape circle)
					(size 0.762 0.762)
					(clearance 0.1651)
				)
				(layer "In9.Cu"
					(shape circle)
					(size 0.762 0.762)
					(clearance 0.1651)
				)
				(layer "In10.Cu"
					(shape circle)
					(size 0.762 0.762)
					(clearance 0.1651)
				)
				(layer "B.Cu"
					(shape circle)
					(size 0.762 0.762)
					(thermal_gap 0.1651)
					(clearance 0.1651)
				)
			)
		)
	)
)
